# BASEBOARD_FAB2 (Tioga Pass) — schematic netlist excerpt (pin names and nets, part order shuffled) for the footprints in the layout excerpt that follows; sources: Cadence DE-HDL packaged netlist, KiCad conversion of Wiwynn_Tioga_Pass_MB.brd

C25W74  CAP  12.0PF 50V 5% COG  pkg 0402LF  page 252 : A = BMC_VGA_RED ; B = GND
C3W2  CAP_A  0.1UF 16V 10% X7R  pkg 0402V  page 249 : A = BMC_TPM_HW_C_RST ; B = GND
R25W123  RES  150.0 1% CHIP  pkg 0402  page 144 : A = BMC_VGA_BLUE ; B = GND

(kicad_pcb
	(version 20260206)
	(generator "pcbnew")
	(generator_version "10.0")
	(general
		(thickness 1.6)
		(legacy_teardrops no)
	)
	(paper "A4")
	(title_block
		(title "Wiwynn_Tioga_Pass_MB.brd")
		(comment 1 "Tioga Pass / footprints 2464-2466 of 4770")
	)
	(layers
		(0 "F.Cu" signal "TOP")
		(4 "In1.Cu" signal "L2GND")
		(6 "In2.Cu" signal "L3")
		(8 "In3.Cu" signal "L4GND")
		(10 "In4.Cu" signal "L5")
		(12 "In5.Cu" signal "L6GND")
		(14 "In6.Cu" signal "L7VCC")
		(16 "In7.Cu" signal "L8VCC")
		(18 "In8.Cu" signal "L9GND")
		(20 "In9.Cu" signal "L10")
		(22 "In10.Cu" signal "L11GND")
		(24 "In11.Cu" signal "L12")
		(26 "In12.Cu" signal "L13GND")
		(2 "B.Cu" signal "BOTTOM")
		(9 "F.Adhes" user "F.Adhesive")
		(11 "B.Adhes" user "B.Adhesive")
		(13 "F.Paste" user "Package Geometry/Pastemask Top")
		(15 "B.Paste" user "Package Geometry/Pastemask Bottom")
		(5 "F.SilkS" user "Ref Des/Silkscreen Top")
		(7 "B.SilkS" user "Ref Des/Silkscreen Bottom")
		(1 "F.Mask" user "Board Geometry/Soldermask Top")
		(3 "B.Mask" user "Board Geometry/Soldermask Bottom")
		(17 "Dwgs.User" user "User.Drawings")
		(19 "Cmts.User" user "User.Comments")
		(21 "Eco1.User" user "User.Eco1")
		(23 "Eco2.User" user "User.Eco2")
		(25 "Edge.Cuts" user "Board Geometry/Outline")
		(27 "Margin" user)
		(31 "F.CrtYd" user "Package Geometry/Place Bound Top")
		(29 "B.CrtYd" user "Package Geometry/Place Bound Bottom")
		(35 "F.Fab" user "Ref Des/Assembly Top")
		(33 "B.Fab" user "Ref Des/Assembly Bottom")
	)
	(footprint ""
		(layer "B.Cu")
		(at 453.8218 -19.7993 180)
		(property "Reference" "C3W2"
			(at 0.8382 -0.67818 180)
			(unlocked yes)
			(layer "B.SilkS")
			(effects
				(font
					(size 0.4064 0.254)
					(thickness 0.1524)
				)
				(justify left mirror)
			)
		)
		(property "Value" ""
			(at 0 0 0)
			(layer "B.Fab")
			(effects
				(font
					(size 1.27 1.27)
				)
				(justify mirror)
			)
		)
		(duplicate_pad_numbers_are_jumpers no)
		(fp_poly
			(pts
				(xy -0.3048 -0.1016) (xy -0.3048 0.9906) (xy 0.3048 0.9906) (xy 0.3048 -0.1016)
			)
			(stroke
				(width 0)
				(type default)
			)
			(fill no)
			(layer "B.CrtYd")
		)
		(fp_line
			(start 0.3048 0.9906)
			(end -0.3048 0.9906)
			(stroke
				(width 0.1)
				(type default)
			)
			(layer "B.Fab")
		)
		(fp_line
			(start 0.3048 -0.1016)
			(end 0.3048 0.9906)
			(stroke
				(width 0.1)
				(type default)
			)
			(layer "B.Fab")
		)
		(fp_line
			(start -0.3048 0.9906)
			(end -0.3048 -0.1016)
			(stroke
				(width 0.1)
				(type default)
			)
			(layer "B.Fab")
		)
		(fp_line
			(start -0.3048 -0.1016)
			(end 0.3048 -0.1016)
			(stroke
				(width 0.1)
				(type default)
			)
			(layer "B.Fab")
		)
		(pad "1" smd rect
			(at 0 0)
			(size 0.508 0.508)
			(layers "B.Cu" "B.Mask" "B.Paste")
			(net "BMC_TPM_HW_C_RST")
		)
		(pad "2" smd rect
			(at 0 0.889)
			(size 0.508 0.508)
			(layers "B.Cu" "B.Mask" "B.Paste")
			(net "GND")
		)
		(zone
			(layer "B.Cu")
			(hatch none 0.5)
			(connect_pads
				(clearance 0)
			)
			(min_thickness 0.25)
			(keepout
				(tracks not_allowed)
				(vias allowed)
				(pads allowed)
				(copperpour not_allowed)
				(footprints allowed)
			)
			(placement
				(enabled no)
				(sheetname "")
			)
			(fill
				(thermal_gap 0.5)
				(thermal_bridge_width 0.5)
				(island_removal_mode 0)
			)
			(polygon
				(pts
					(xy 453.5678 -20.4343) (xy 454.0758 -20.4343) (xy 454.0758 -20.0533) (xy 453.5678 -20.0533)
				)
			)
		)
		(zone
			(layer "B.Cu")
			(hatch none 0.5)
			(connect_pads
				(clearance 0)
			)
			(min_thickness 0.25)
			(keepout
				(tracks allowed)
				(vias not_allowed)
				(pads allowed)
				(copperpour not_allowed)
				(footprints allowed)
			)
			(placement
				(enabled no)
				(sheetname "")
			)
			(fill
				(thermal_gap 0.5)
				(thermal_bridge_width 0.5)
				(island_removal_mode 0)
			)
			(polygon
				(pts
					(xy 453.5678 -20.0533) (xy 454.0758 -20.0533) (xy 454.0758 -20.4343) (xy 453.5678 -20.4343)
				)
			)
		)
	)
	(footprint ""
		(layer "B.Cu")
		(at 416.9664 -22.225)
		(property "Reference" "R25W123"
			(at 0.8382 -0.67818 0)
			(unlocked yes)
			(layer "B.SilkS")
			(effects
				(font
					(size 0.4064 0.254)
					(thickness 0.1524)
				)
				(justify left mirror)
			)
		)
		(property "Value" ""
			(at 0 0 0)
			(layer "B.Fab")
			(effects
				(font
					(size 1.27 1.27)
				)
				(justify mirror)
			)
		)
		(duplicate_pad_numbers_are_jumpers no)
		(fp_poly
			(pts
				(xy 0.2794 -0.1016) (xy -0.2794 -0.1016) (xy -0.2794 0.9906) (xy 0.2794 0.9906)
			)
			(stroke
				(width 0)
				(type default)
			)
			(fill no)
			(layer "B.CrtYd")
		)
		(fp_line
			(start -0.2794 -0.1016)
			(end 0.2794 -0.1016)
			(stroke
				(width 0.1)
				(type default)
			)
			(layer "B.Fab")
		)
		(fp_line
			(start -0.2794 0.9906)
			(end -0.2794 -0.1016)
			(stroke
				(width 0.1)
				(type default)
			)
			(layer "B.Fab")
		)
		(fp_line
			(start 0.2794 -0.1016)
			(end 0.2794 0.9906)
			(stroke
				(width 0.1)
				(type default)
			)
			(layer "B.Fab")
		)
		(fp_line
			(start 0.2794 0.9906)
			(end -0.2794 0.9906)
			(stroke
				(width 0.1)
				(type default)
			)
			(layer "B.Fab")
		)
		(pad "1" smd rect
			(at 0 0 180)
			(size 0.508 0.508)
			(layers "B.Cu" "B.Mask" "B.Paste")
			(net "BMC_VGA_BLUE")
		)
		(pad "2" smd rect
			(at 0 0.889 180)
			(size 0.508 0.508)
			(layers "B.Cu" "B.Mask" "B.Paste")
			(net "GND")
		)
		(zone
			(layer "B.Cu")
			(hatch none 0.5)
			(connect_pads
				(clearance 0)
			)
			(min_thickness 0.25)
			(keepout
				(tracks allowed)
				(vias not_allowed)
				(pads allowed)
				(copperpour not_allowed)
				(footprints allowed)
			)
			(placement
				(enabled no)
				(sheetname "")
			)
			(fill
				(thermal_gap 0.5)
				(thermal_bridge_width 0.5)
				(island_removal_mode 0)
			)
			(polygon
				(pts
					(xy 417.2204 -21.971) (xy 416.7124 -21.971) (xy 416.7124 -21.59) (xy 417.2204 -21.59)
				)
			)
		)
		(zone
			(layer "B.Cu")
			(hatch none 0.5)
			(connect_pads
				(clearance 0)
			)
			(min_thickness 0.25)
			(keepout
				(tracks not_allowed)
				(vias allowed)
				(pads allowed)
				(copperpour not_allowed)
				(footprints allowed)
			)
			(placement
				(enabled no)
				(sheetname "")
			)
			(fill
				(thermal_gap 0.5)
				(thermal_bridge_width 0.5)
				(island_removal_mode 0)
			)
			(polygon
				(pts
					(xy 417.2204 -21.59) (xy 416.7124 -21.59) (xy 416.7124 -21.971) (xy 417.2204 -21.971)
				)
			)
		)
	)
	(footprint ""
		(layer "B.Cu")
		(at 416.179 -26.035)
		(property "Reference" "C25W74"
			(at 0.8382 -0.67818 0)
			(unlocked yes)
			(layer "B.SilkS")
			(effects
				(font
					(size 0.4064 0.254)
					(thickness 0.1524)
				)
				(justify left mirror)
			)
		)
		(property "Value" ""
			(at 0 0 0)
			(layer "B.Fab")
			(effects
				(font
					(size 1.27 1.27)
				)
				(justify mirror)
			)
		)
		(duplicate_pad_numbers_are_jumpers no)
		(fp_poly
			(pts
				(xy -0.3048 -0.1016) (xy -0.3048 0.9906) (xy 0.3048 0.9906) (xy 0.3048 -0.1016)
			)
			(stroke
				(width 0)
				(type default)
			)
			(fill no)
			(layer "B.CrtYd")
		)
		(fp_line
			(start -0.3048 -0.1016)
			(end 0.3048 -0.1016)
			(stroke
				(width 0.1)
				(type default)
			)
			(layer "B.Fab")
		)
		(fp_line
			(start -0.3048 0.9906)
			(end -0.3048 -0.1016)
			(stroke
				(width 0.1)
				(type default)
			)
			(layer "B.Fab")
		)
		(fp_line
			(start 0.3048 -0.1016)
			(end 0.3048 0.9906)
			(stroke
				(width 0.1)
				(type default)
			)
			(layer "B.Fab")
		)
		(fp_line
			(start 0.3048 0.9906)
			(end -0.3048 0.9906)
			(stroke
				(width 0.1)
				(type default)
			)
			(layer "B.Fab")
		)
		(pad "1" smd rect
			(at 0 0 180)
			(size 0.508 0.508)
			(layers "B.Cu" "B.Mask" "B.Paste")
			(net "BMC_VGA_RED")
		)
		(pad "2" smd rect
			(at 0 0.889 180)
			(size 0.508 0.508)
			(layers "B.Cu" "B.Mask" "B.Paste")
			(net "GND")
		)
		(zone
			(layer "B.Cu")
			(hatch none 0.5)
			(connect_pads
				(clearance 0)
			)
			(min_thickness 0.25)
			(keepout
				(tracks allowed)
				(vias not_allowed)
				(pads allowed)
				(copperpour not_allowed)
				(footprints allowed)
			)
			(placement
				(enabled no)
				(sheetname "")
			)
			(fill
				(thermal_gap 0.5)
				(thermal_bridge_width 0.5)
				(island_removal_mode 0)
			)
			(polygon
				(pts
					(xy 416.433 -25.781) (xy 415.925 -25.781) (xy 415.925 -25.4) (xy 416.433 -25.4)
				)
			)
		)
		(zone
			(layer "B.Cu")
			(hatch none 0.5)
			(connect_pads
				(clearance 0)
			)
			(min_thickness 0.25)
			(keepout
				(tracks not_allowed)
				(vias allowed)
				(pads allowed)
				(copperpour not_allowed)
				(footprints allowed)
			)
			(placement
				(enabled no)
				(sheetname "")
			)
			(fill
				(thermal_gap 0.5)
				(thermal_bridge_width 0.5)
				(island_removal_mode 0)
			)
			(polygon
				(pts
					(xy 416.433 -25.4) (xy 415.925 -25.4) (xy 415.925 -25.781) (xy 416.433 -25.781)
				)
			)
		)
	)
)
